FILE_TYPE=LIBRARY_PARTS;
primitive 'CONN17_H71061002','CONN17_H71061002_PIP','CONN17_H71061002_PIP1';
  pin
    'MH2':
      PIN_NUMBER='(MH2)';
      PINUSE='GROUND';
      NO_LOAD_CHECK='Both';
      NO_IO_CHECK='Both';
      NO_ASSERT_CHECK='TRUE';
      NO_DIR_CHECK='TRUE';
      ALLOW_CONNECT='TRUE';
    'MH1':
      PIN_NUMBER='(MH1)';
      PINUSE='GROUND';
      NO_LOAD_CHECK='Both';
      NO_IO_CHECK='Both';
      NO_ASSERT_CHECK='TRUE';
      NO_DIR_CHECK='TRUE';
      ALLOW_CONNECT='TRUE';
    'TRCT3':
      PIN_NUMBER='(R1)';
      BIDIRECTIONAL='TRUE';
      INPUT_LOAD='(-0.01,0.01)';
      OUTPUT_LOAD='(1.0,-1.0)';
    'TRD3N':
      PIN_NUMBER='(R2)';
      BIDIRECTIONAL='TRUE';
      INPUT_LOAD='(-0.01,0.01)';
      OUTPUT_LOAD='(1.0,-1.0)';
    'TRD3P':
      PIN_NUMBER='(R3)';
      BIDIRECTIONAL='TRUE';
      INPUT_LOAD='(-0.01,0.01)';
      OUTPUT_LOAD='(1.0,-1.0)';
    'TRD2P':
      PIN_NUMBER='(R4)';
      BIDIRECTIONAL='TRUE';
      INPUT_LOAD='(-0.01,0.01)';
      OUTPUT_LOAD='(1.0,-1.0)';
    'TRD2N':
      PIN_NUMBER='(R5)';
      BIDIRECTIONAL='TRUE';
      INPUT_LOAD='(-0.01,0.01)';
      OUTPUT_LOAD='(1.0,-1.0)';
    'TRCT2':
      PIN_NUMBER='(R6)';
      BIDIRECTIONAL='TRUE';
      INPUT_LOAD='(-0.01,0.01)';
      OUTPUT_LOAD='(1.0,-1.0)';
    'TRCT4':
      PIN_NUMBER='(R7)';
      BIDIRECTIONAL='TRUE';
      INPUT_LOAD='(-0.01,0.01)';
      OUTPUT_LOAD='(1.0,-1.0)';
    'TRD4P':
      PIN_NUMBER='(R8)';
      BIDIRECTIONAL='TRUE';
      INPUT_LOAD='(-0.01,0.01)';
      OUTPUT_LOAD='(1.0,-1.0)';
    'TRD4N':
      PIN_NUMBER='(R9)';
      BIDIRECTIONAL='TRUE';
      INPUT_LOAD='(-0.01,0.01)';
      OUTPUT_LOAD='(1.0,-1.0)';
    'TRD1N':
      PIN_NUMBER='(R10)';
      BIDIRECTIONAL='TRUE';
      INPUT_LOAD='(-0.01,0.01)';
      OUTPUT_LOAD='(1.0,-1.0)';
    'TRD1P':
      PIN_NUMBER='(R11)';
      BIDIRECTIONAL='TRUE';
      INPUT_LOAD='(-0.01,0.01)';
      OUTPUT_LOAD='(1.0,-1.0)';
    'TRCT1':
      PIN_NUMBER='(R12)';
      BIDIRECTIONAL='TRUE';
      INPUT_LOAD='(-0.01,0.01)';
      OUTPUT_LOAD='(1.0,-1.0)';
    'L3':
      PIN_NUMBER='(L3)';
      BIDIRECTIONAL='TRUE';
      INPUT_LOAD='(-0.01,0.01)';
      OUTPUT_LOAD='(1.0,-1.0)';
    'L2':
      PIN_NUMBER='(L2)';
      BIDIRECTIONAL='TRUE';
      INPUT_LOAD='(-0.01,0.01)';
      OUTPUT_LOAD='(1.0,-1.0)';
    'L1':
      PIN_NUMBER='(L1)';
      BIDIRECTIONAL='TRUE';
      INPUT_LOAD='(-0.01,0.01)';
      OUTPUT_LOAD='(1.0,-1.0)';
    'L5':
      PIN_NUMBER='(L5)';
      BIDIRECTIONAL='TRUE';
      INPUT_LOAD='(-0.01,0.01)';
      OUTPUT_LOAD='(1.0,-1.0)';
    'L4':
      PIN_NUMBER='(L4)';
      BIDIRECTIONAL='TRUE';
      INPUT_LOAD='(-0.01,0.01)';
      OUTPUT_LOAD='(1.0,-1.0)';
  end_pin;
  body
    PART_NAME='CONN17_H71061002';
    PHYS_DES_PREFIX='JA';
  end_body;
end_primitive;

END.
